# S9S_MB_2U (Grand Teton) — schematic parts with pin connectivity, parts 5876–5876 of 6093; source: Cadence DE-HDL packaged netlist (pstxprt.dat, pstxnet.dat, pstchip.dat)

U1  SOCKET4677_AZIF0045P001C01CS  SOCKET4677_AZIF0045-P001C01CS IO  pkg SOCKET4677_82X64-5XA_H466  page 44  (pins 1636-1962 of 4677)
  C7  DDR0_SB_DQ29  BI  = M_A_CPU1_SB_DQ<29>
  C9  DDR0_SB_DQS_DP3  BI  = M_A_CPU1_SB_DQS_DP<3>
  C11  DDR0_SB_DQ24  BI  = M_A_CPU1_SB_DQ<24>
  C13  DDR1_SB_DQ28  BI  = M_B_CPU1_SB_DQ<28>
  C15  DDR1_SB_DQS_DP3  BI  = M_B_CPU1_SB_DQS_DP<3>
  C17  DDR1_SB_DQ24  BI  = M_B_CPU1_SB_DQ<24>
  C19  DDR0_SB_DQ21  BI  = M_A_CPU1_SB_DQ<21>
  C21  DDR0_SB_DQS_DP2  BI  = M_A_CPU1_SB_DQS_DP<2>
  C23  DDR0_SB_DQ16  BI  = M_A_CPU1_SB_DQ<16>
  C25  DDR0_SB_DQ13  BI  = M_A_CPU1_SB_DQ<13>
  C27  DDR0_SB_DQS_DP1  BI  = M_A_CPU1_SB_DQS_DP<1>
  C29  DDR0_SB_DQ8  BI  = M_A_CPU1_SB_DQ<8>
  C31  DDR0_SB_ECC1  BI  = M_A_CPU1_SB_CB<1>
  C33  DDR0_SB_DQS_DP9  BI  = M_A_CPU1_SB_DQS_DP<9>
  C35  DDR0_SB_ECC4  BI  = M_A_CPU1_SB_CB<4>
  C37  DDR0_SB_CS_N1  OUT  = M_A_CPU1_SB_CS_N<1>
  C39  VSS609  POWER  = GND
  C41  DDR0_SB_CA2  OUT  = M_A_CPU1_SB_CA<2>
  C43  DDR0_CLK_DP0  OUT  = M_A_CPU1_CLK_DP<0>
  C45  VSS610  POWER  = GND
  C48  DDR0_SA_CA6  OUT  = M_A_CPU1_SA_CA<6>
  C50  DDR0_SA_CA4  OUT  = M_A_CPU1_SA_CA<4>
  C52  VSS613  POWER  = GND
  C54  DDR0_SA_CS_N0  OUT  = M_A_CPU1_SA_CS_N<0>
  C56  DDR0_SA_ECC5  BI  = M_A_CPU1_SA_CB<5>
  C58  DDR0_SA_DQS_DP4  BI  = M_A_CPU1_SA_DQS_DP<4>
  C60  DDR0_SA_ECC0  BI  = M_A_CPU1_SA_CB<0>
  C62  DDR0_SA_DQ29  BI  = M_A_CPU1_SA_DQ<29>
  C64  DDR0_SA_DQS_DP3  BI  = M_A_CPU1_SA_DQS_DP<3>
  C66  DDR0_SA_DQ24  BI  = M_A_CPU1_SA_DQ<24>
  C68  DDR0_SA_DQ21  BI  = M_A_CPU1_SA_DQ<21>
  C70  DDR0_SA_DQS_DP2  BI  = M_A_CPU1_SA_DQS_DP<2>
  C72  VSS614  POWER  = GND
  C74  VSS615  POWER  = GND
  C76  DDR0_SA_DQ4  BI  = M_A_CPU1_SA_DQ<4>
  C78  VSS616  POWER  = GND
  C80  VSS617  POWER  = GND
  C82  VSS618  POWER  = GND
  C84  VCCFA_EHV_FIVRA32  POWER  = PVCCFA_EHV_FIVRA_CPU1
  C86  VSS619  POWER  = GND
  C88  VCCFA_EHV_FIVRA33  POWER  = PVCCFA_EHV_FIVRA_CPU1
  CA3  VSS620  POWER  = GND
  CA5  UPI1_TX_DN22  OUT  = UPI_CPU1_CPU0_P1P0_DN<22>
  CA7  VCCD_HV19  POWER  = PVCCD_HV_CPU1
  CA9  PE1_RX_DP6  IN  = P5E_CPU1_PE1_RX_DP<6>
  CA11  VCCINFAON_SENSE  POWER  = VSENSE_PVCCINFAON_CPU1_DP
  CA13  PE1_TX_DN7  OUT  = P5E_CPU1_PE1_TX_DN<7>
  CA15  VCCINFAON43  POWER  = PVCCINFAON_CPU1
  CA17  DMI_TX_DN1  OUT  = TP_DMI_CPU1_PCH_TX_DN<1>
  CA19  DMI_TX_DP0  OUT  = TP_DMI_CPU1_PCH_TX_DP<0>
  CA21  RSVD77  BI  = NC_CPU1_DMI_APROBE<0>
  CA23  RSVD78  BI  = NC_CPU1_UPI1_APROBE<1>
  CA25  CXPSMBUSSCL  OUT  = SMB_PEHPCPU1_GTL_SCL
  CA27  PTI_DIE006  OUT  = TP_TRC_CPU1_PTI<6>
  CA29  PTI_DIE004  OUT  = TP_TRC_CPU1_PTI<4>
  CA31  VSS621  POWER  = GND
  CA33  VCCIN225  POWER  = PVCCIN_CPU1
  CA35  VCCIN226  POWER  = PVCCIN_CPU1
  CA37  VCCIN227  POWER  = PVCCIN_CPU1
  CA39  VCCIN228  POWER  = PVCCIN_CPU1
  CA41  VCCIN229  POWER  = PVCCIN_CPU1
  CA43  VCCIN230  POWER  = PVCCIN_CPU1
  CA45  VCCIN231  POWER  = PVCCIN_CPU1
  CA48  VCCIN232  POWER  = PVCCIN_CPU1
  CA50  VCCIN233  POWER  = PVCCIN_CPU1
  CA52  VCCIN234  POWER  = PVCCIN_CPU1
  CA54  VCCIN235  POWER  = PVCCIN_CPU1
  CA56  VCCIN236  POWER  = PVCCIN_CPU1
  CA58  VCCIN237  POWER  = PVCCIN_CPU1
  CA60  VCCIN238  POWER  = PVCCIN_CPU1
  CA62  VCCIN239  POWER  = PVCCIN_CPU1
  CA64  VCCIN240  POWER  = PVCCIN_CPU1
  CA66  VCCIN241  POWER  = PVCCIN_CPU1
  CA68  VCCIN242  POWER  = PVCCIN_CPU1
  CA70  VCCIN243  POWER  = PVCCIN_CPU1
  CA72  VCCIN244  POWER  = PVCCIN_CPU1
  CA74  VCCIN245  POWER  = PVCCIN_CPU1
  CA76  VCCIN246  POWER  = PVCCIN_CPU1
  CA78  VCCIN247  POWER  = PVCCIN_CPU1
  CA80  VCCIN248  POWER  = PVCCIN_CPU1
  CA82  VCCIN249  POWER  = PVCCIN_CPU1
  CA84  VCCIN250  POWER  = PVCCIN_CPU1
  CA86  VCCIN251  POWER  = PVCCIN_CPU1
  CA88  VCCIN252  POWER  = PVCCIN_CPU1
  CA90  VCCIN253  POWER  = PVCCIN_CPU1
  CB2  UPI1_RX_DN23  IN  = UPI_CPU0_CPU1_P0P1_DN<23>
  CB4  VSS633  POWER  = GND
  CB6  UPI1_TX_DP22  OUT  = UPI_CPU1_CPU0_P1P0_DP<22>
  CB8  VSS651  POWER  = GND
  CB10  PE1_RX_DN6  IN  = P5E_CPU1_PE1_RX_DN<6>
  CB12  VSS622  POWER  = GND
  CB14  PE1_TX_DN6  OUT  = P5E_CPU1_PE1_TX_DN<6>
  CB16  VSS623  POWER  = GND
  CB18  DMI_TX_DN2  OUT  = TP_DMI_CPU1_PCH_TX_DN<2>
  CB20  VSS624  POWER  = GND
  CB22  VSS625  POWER  = GND
  CB24  VSS626  POWER  = GND
  CB26  VSS627  POWER  = GND
  CB28  VSS628  POWER  = GND
  CB30  PTI_DIE00_STB_0  OUT  = TP_TRC_CPU1_PTI0_CLK
  CB32  VSS629  POWER  = GND
  CB34  VSS630  POWER  = GND
  CB36  VSS631  POWER  = GND
  CB38  VSS632  POWER  = GND
  CB40  VSS634  POWER  = GND
  CB42  VSS635  POWER  = GND
  CB44  VSS636  POWER  = GND
  CB47  VSS637  POWER  = GND
  CB49  VSS638  POWER  = GND
  CB51  VSS639  POWER  = GND
  CB53  VSS640  POWER  = GND
  CB55  VSS641  POWER  = GND
  CB57  VSS642  POWER  = GND
  CB59  VSS643  POWER  = GND
  CB61  VCCIN254  POWER  = PVCCIN_CPU1
  CB63  VSS644  POWER  = GND
  CB65  VSS645  POWER  = GND
  CB67  VSS646  POWER  = GND
  CB69  VSS647  POWER  = GND
  CB71  VSS648  POWER  = GND
  CB73  VSS649  POWER  = GND
  CB75  VCCIN255  POWER  = PVCCIN_CPU1
  CB77  VCCIN256  POWER  = PVCCIN_CPU1
  CB79  VSS650  POWER  = GND
  CB81  VSS652  POWER  = GND
  CB83  VSS653  POWER  = GND
  CB85  VSS654  POWER  = GND
  CB87  VSS655  POWER  = GND
  CB89  VSS656  POWER  = GND
  CC3  UPI1_RX_DP22  IN  = UPI_CPU0_CPU1_P0P1_DP<22>
  CC5  VSS665  POWER  = GND
  CC7  UPI1_TX_DP21  OUT  = UPI_CPU1_CPU0_P1P0_DP<21>
  CC9  VSS670  POWER  = GND
  CC11  PE1_RX_DN5  IN  = P5E_CPU1_PE1_RX_DN<5>
  CC13  VSS660  POWER  = GND
  CC15  PE1_TX_DP6  OUT  = P5E_CPU1_PE1_TX_DP<6>
  CC17  VSS661  POWER  = GND
  CC19  DMI_TX_DP2  OUT  = TP_DMI_CPU1_PCH_TX_DP<2>
  CC21  RSVD79  BI  = NC_CPU1_PE1_APROBE<1>
  CC23  RSVD80  BI  = NC_CPU1_PE2_APROBE<0>
  CC25  PMDOWN6  BI  = TP_H_SBLINK7_CPU1_PMDOWN
  CC27  PTI_DIE002  OUT  = TP_TRC_CPU1_PTI<2>
  CC29  PTI_DIE000  OUT  = TP_TRC_CPU1_PTI<0>
  CC31  VSS664  POWER  = GND
  CC33  VCCIN257  POWER  = PVCCIN_CPU1
  CC35  VCCIN258  POWER  = PVCCIN_CPU1
  CC37  VCCIN259  POWER  = PVCCIN_CPU1
  CC39  VCCIN260  POWER  = PVCCIN_CPU1
  CC41  VCCIN261  POWER  = PVCCIN_CPU1
  CC43  VCCIN262  POWER  = PVCCIN_CPU1
  CC45  VCCIN263  POWER  = PVCCIN_CPU1
  CC48  VCCIN264  POWER  = PVCCIN_CPU1
  CC50  VCCIN265  POWER  = PVCCIN_CPU1
  CC52  VCCIN266  POWER  = PVCCIN_CPU1
  CC54  VCCIN267  POWER  = PVCCIN_CPU1
  CC56  VCCIN268  POWER  = PVCCIN_CPU1
  CC58  VCCIN269  POWER  = PVCCIN_CPU1
  CC60  VCCIN270  POWER  = PVCCIN_CPU1
  CC62  VSS666  POWER  = GND
  CC64  RSVD81  BI  = NC_CPU1_LGSSPARE4
  CC66  RSVD82  BI  = NC_CPU1_MDFI_DIE01_EW1
  CC68  VPP_HBM4  POWER  = PVPP_HBM_CPU1
  CC70  VSS667  POWER  = GND
  CC72  VSS668  POWER  = GND
  CC74  VSS669  POWER  = GND
  CC76  VCCIN271  POWER  = PVCCIN_CPU1
  CC78  VCCIN272  POWER  = PVCCIN_CPU1
  CC80  VCCIN273  POWER  = PVCCIN_CPU1
  CC82  VCCIN274  POWER  = PVCCIN_CPU1
  CC84  VCCIN275  POWER  = PVCCIN_CPU1
  CC86  VCCIN276  POWER  = PVCCIN_CPU1
  CC88  VCCIN277  POWER  = PVCCIN_CPU1
  CC90  VCCIN278  POWER  = PVCCIN_CPU1
  CD2  UPI1_RX_DN22  IN  = UPI_CPU0_CPU1_P0P1_DN<22>
  CD4  VSS674  POWER  = GND
  CD6  UPI1_TX_DN21  OUT  = UPI_CPU1_CPU0_P1P0_DN<21>
  CD8  VSS678  POWER  = GND
  CD10  PE1_RX_DP5  IN  = P5E_CPU1_PE1_RX_DP<5>
  CD12  VSS671  POWER  = GND
  CD14  PE1_TX_DP5  OUT  = P5E_CPU1_PE1_TX_DP<5>
  CD16  VSS672  POWER  = GND
  CD18  DMI_TX_DP3  OUT  = TP_DMI_CPU1_PCH_TX_DP<3>
  CD20  VSS673  POWER  = GND
  CD22  RSVD83  BI  = NC_CPU1_MDFI_DIE10_NS1
  CD24  PMDOWN3  BI  = TP_H_SBLINK4_CPU1_PMDOWN
  CD26  RSVD84  BI  = NC_CPU1_MDFI_DIE10_EW0
  CD28  PTI_DIE001  OUT  = TP_TRC_CPU1_PTI<1>
  CD30  RSVD85  BI  = NC_CPU1_MDFI_DIE10_EW1
  CD32  VCCIN279  POWER  = PVCCIN_CPU1
  CD34  VCCIN280  POWER  = PVCCIN_CPU1
  CD36  VCCIN281  POWER  = PVCCIN_CPU1
  CD38  VCCIN282  POWER  = PVCCIN_CPU1
  CD40  VCCIN283  POWER  = PVCCIN_CPU1
  CD42  VCCIN284  POWER  = PVCCIN_CPU1
  CD44  VCCIN285  POWER  = PVCCIN_CPU1
  CD47  VCCIN286  POWER  = PVCCIN_CPU1
  CD49  VCCIN287  POWER  = PVCCIN_CPU1
  CD51  VCCIN288  POWER  = PVCCIN_CPU1
  CD53  VCCIN289  POWER  = PVCCIN_CPU1
  CD55  VCCIN290  POWER  = PVCCIN_CPU1
  CD57  VCCIN291  POWER  = PVCCIN_CPU1
  CD59  VCCIN292  POWER  = PVCCIN_CPU1
  CD61  VSS675  POWER  = GND
  CD63  SMB_DATA  BI  = SMB_S3M_CPU1_SDA
  CD65  RSVD86  BI  = TP_SGPIO_S3M_CPU1_GSXRST_N
  CD67  VPP_HBM3  POWER  = PVPP_HBM_CPU1
  CD69  RSVD87  BI  = TP_CPU1_SPARE11
  CD71  RSVD88  BI  = CPU1_RSVD<82>
  CD73  UPI3_TX_DP23  OUT  = NC
  CD75  VSS676  POWER  = GND
  CD77  VSS677  POWER  = GND
  CD79  VCCIN293  POWER  = PVCCIN_CPU1
  CD81  VCCIN294  POWER  = PVCCIN_CPU1
  CD83  VCCIN295  POWER  = PVCCIN_CPU1
  CD85  VCCIN296  POWER  = PVCCIN_CPU1
  CD87  VCCIN297  POWER  = PVCCIN_CPU1
  CD89  VCCIN298  POWER  = PVCCIN_CPU1
  CE1  UPI1_RX_DP21  IN  = UPI_CPU0_CPU1_P0P1_DP<21>
  CE3  VSS680  POWER  = GND
  CE5  UPI1_TX_DN20  OUT  = UPI_CPU1_CPU0_P1P0_DN<20>
  CE7  VCCD_HV20  POWER  = PVCCD_HV_CPU1
  CE9  PE1_RX_DP4  IN  = P5E_CPU1_PE1_RX_DP<4>
  CE11  VSS_VCCINFAON_SENSE  POWER  = VSENSE_PVCCINFAON_CPU1_DN
  CE13  PE1_TX_DN5  OUT  = P5E_CPU1_PE1_TX_DN<5>
  CE15  VCCINFAON0  POWER  = PVCCINFAON_CPU1
  CE17  DMI_TX_DN3  OUT  = TP_DMI_CPU1_PCH_TX_DN<3>
  CE19  VCCINFAON44  POWER  = PVCCINFAON_CPU1
  CE21  RSVD89  BI  = NC_CPU1_PE1_APROBE<0>
  CE23  PMDOWN5  BI  = TP_H_SBLINK6_CPU1_PMDOWN
  CE25  PMSYNC3  BI  = TP_H_SBLINK4_CPU1_PMSYNC
  CE60  VSS681  POWER  = GND
  CE62  RSVD90  BI  = NC_CPU1_LGSSPARE3
  CE64  SMB_CLK  OUT  = SMB_S3M_CPU1_SCL
  CE66  VSS682  POWER  = GND
  CE68  VPP_HBM2  POWER  = PVPP_HBM_CPU1
  CE70  RSVD91  BI  = CPU1_RSVD<85>
  CE72  VSS683  POWER  = GND
  CE74  VCCFA_EHV_FIVRA34  POWER  = PVCCFA_EHV_FIVRA_CPU1
  CE76  VSS684  POWER  = GND
  CE78  VSS685  POWER  = GND
  CE80  VCCIN299  POWER  = PVCCIN_CPU1
  CE82  VCCIN300  POWER  = PVCCIN_CPU1
  CE84  VCCIN301  POWER  = PVCCIN_CPU1
  CE86  VCCIN302  POWER  = PVCCIN_CPU1
  CE88  VCCIN303  POWER  = PVCCIN_CPU1
  CE90  VCCIN304  POWER  = PVCCIN_CPU1
  CF2  UPI1_RX_DN21  IN  = UPI_CPU0_CPU1_P0P1_DN<21>
  CF4  VSS689  POWER  = GND
  CF6  UPI1_TX_DP20  OUT  = UPI_CPU1_CPU0_P1P0_DP<20>
  CF8  VSS693  POWER  = GND
  CF10  PE1_RX_DN4  IN  = P5E_CPU1_PE1_RX_DN<4>
  CF12  VSS686  POWER  = GND
  CF14  PE1_TX_DN4  OUT  = P5E_CPU1_PE1_TX_DN<4>
  CF16  VSS687  POWER  = GND
  CF18  DMI_TX_DN4  OUT  = TP_DMI_CPU1_PCH_TX_DN<4>
  CF20  VSS688  POWER  = GND
  CF22  RSVD92  BI  = NC_CPU1_MDFI_DIE10_NS0
  CF24  PMSYNC6  BI  = TP_H_SBLINK7_CPU1_PMSYNC
  CF26  MEMHOT_OUT_N  OUT  = H_CPU1_MEMHOT_OUT_LVC1_R_N
  CF61  TEST_6  BI  = PUD_PCH_BOOT_MODE_CPU1
  CF63  RSVD93  BI  = TP_SGPIO_S3M_CPU1_GSXCLK
  CF65  RSVD94  BI  = TP_SGPIO_S3M_CPU1_GSXDOUT
  CF67  VPP_HBM1  POWER  = PVPP_HBM_CPU1
  CF69  VSS691  POWER  = GND
  CF71  VSS692  POWER  = GND
  CF73  UPI3_TX_DN23  OUT  = NC
  CF75  UPI3_TX_DN20  OUT  = NC
  CF77  UPI3_TX_DP19  OUT  = NC
  CF79  VCCIN305  POWER  = PVCCIN_CPU1
  CF81  VCCIN306  POWER  = PVCCIN_CPU1
  CF83  VCCIN307  POWER  = PVCCIN_CPU1
  CF85  VCCIN308  POWER  = PVCCIN_CPU1
  CF87  VCCIN309  POWER  = PVCCIN_CPU1
  CF89  VCCIN310  POWER  = PVCCIN_CPU1
  CF91  VCCIN311  POWER  = PVCCIN_CPU1
  CG1  VSS694  POWER  = GND
  CG3  UPI1_RX_DP20  IN  = UPI_CPU0_CPU1_P0P1_DP<20>
  CG5  VSS703  POWER  = GND
  CG7  UPI1_TX_DP19  OUT  = UPI_CPU1_CPU0_P1P0_DP<19>
  CG9  VSS716  POWER  = GND
  CG11  PE1_RX_DN3  IN  = P5E_CPU1_PE1_RX_DN<3>
  CG13  VSS695  POWER  = GND
  CG15  PE1_TX_DP4  OUT  = P5E_CPU1_PE1_TX_DP<4>
  CG17  VSS696  POWER  = GND
  CG19  DMI_TX_DP4  OUT  = TP_DMI_CPU1_PCH_TX_DP<4>
  CG21  VSS697  POWER  = GND
  CG23  VSS698  POWER  = GND
  CG25  VSS701  POWER  = GND
  CG60  RSVD95  BI  = TP_CPU1_SPARE10
  CG62  VSS704  POWER  = GND
  CG64  VSS706  POWER  = GND
  CG66  SKTOCC_N  OUT  = FM_CPU1_SKTOCC_LVT3_N
  CG68  VPP_HBM  POWER  = PVPP_HBM_CPU1
  CG70  VSS707  POWER  = GND
  CG72  VSS708  POWER  = GND
  CG74  VSS710  POWER  = GND
  CG76  UPI3_TX_DN19  OUT  = NC
  CG78  VSS713  POWER  = GND
  CG80  VCCIN312  POWER  = PVCCIN_CPU1
  CG82  VCCIN313  POWER  = PVCCIN_CPU1
  CG84  VCCIN314  POWER  = PVCCIN_CPU1
  CG86  VCCIN315  POWER  = PVCCIN_CPU1
  CG88  VCCIN316  POWER  = PVCCIN_CPU1
  CG90  VCCIN317  POWER  = PVCCIN_CPU1
  CH2  UPI1_RX_DN20  IN  = UPI_CPU0_CPU1_P0P1_DN<20>
  CH4  VSS722  POWER  = GND
  CH6  UPI1_TX_DN19  OUT  = UPI_CPU1_CPU0_P1P0_DN<19>
  CH8  VSS730  POWER  = GND
  CH10  PE1_RX_DP3  IN  = P5E_CPU1_PE1_RX_DP<3>
  CH12  VSS718  POWER  = GND
  CH14  PE1_TX_DP3  OUT  = P5E_CPU1_PE1_TX_DP<3>
  CH16  VSS720  POWER  = GND
  CH18  DMI_TX_DP5  OUT  = TP_DMI_CPU1_PCH_TX_DP<5>
  CH20  VSS721  POWER  = GND
  CH22  RSVD96  BI  = PD_CPU1_ENH_MCECC_DIS
  CH24  PMSYNC5  BI  = TP_H_SBLINK6_CPU1_PMSYNC
  CH26  PMSYNC2  BI  = TP_H_SBLINK3_CPU1_PMSYNC
  CH61  RSVD97  BI  = TP_CPU1_SPARE9
  CH63  RSVD98  BI  = TP_SGPIO_S3M_CPU1_GSXDIN
  CH65  TEST_3  BI  = PU_S3M_CPU1_CPLD_STATUS
  CH67  VSS727  POWER  = GND
  CH69  RSVD99  BI  = NC_CPU1_MDFI_DIE11_EW1
  CH71  RSVD100  BI  = TP_PWRGD_S0_PWROK_CPU1_LVC1
  CH73  VSS728  POWER  = GND
  CH75  UPI3_TX_DP20  OUT  = NC
  CH77  UPI3_TX_DN17  OUT  = NC
  CH79  VSS729  POWER  = GND
